FILE_TYPE = CONNECTIVITY;
{Allegro Design Entry HDL 17.4-2019 S026 (4007227) 1/17/2022}
"PAGE_NUMBER" = 413;
0"NC";
END.
